(kicad_pcb
	(version 20260206)
	(generator "pcbnew")
	(generator_version "10.0")
	(general
		(thickness 1.6)
		(legacy_teardrops no)
	)
	(paper "A4")
	(title_block
		(title "12092022_DA0F0TFB6D0_F0T_FAN_BOARD_MP5048_D_brd_v02_OCP.brd")
		(comment 1 "Grand Teton / footprints 135-140 of 924")
	)
	(layers
		(0 "F.Cu" signal "TOP")
		(4 "In1.Cu" signal "GND")
		(6 "In2.Cu" signal "IN1")
		(8 "In3.Cu" signal "IN2")
		(10 "In4.Cu" signal "GND1")
		(2 "B.Cu" signal "BOTTOM")
		(9 "F.Adhes" user "F.Adhesive")
		(11 "B.Adhes" user "B.Adhesive")
		(13 "F.Paste" user "Package Geometry/Pastemask Top")
		(15 "B.Paste" user "Package Geometry/Pastemask Bottom")
		(5 "F.SilkS" user "Ref Des/Silkscreen Top")
		(7 "B.SilkS" user "Ref Des/Silkscreen Bottom")
		(1 "F.Mask" user "Board Geometry/Soldermask Top")
		(3 "B.Mask" user "Board Geometry/Soldermask Bottom")
		(17 "Dwgs.User" user "User.Drawings")
		(19 "Cmts.User" user "User.Comments")
		(21 "Eco1.User" user "User.Eco1")
		(23 "Eco2.User" user "User.Eco2")
		(25 "Edge.Cuts" user "Board Geometry/Outline")
		(27 "Margin" user)
		(31 "F.CrtYd" user "Package Geometry/Place Bound Top")
		(29 "B.CrtYd" user "Package Geometry/Place Bound Bottom")
		(35 "F.Fab" user "Ref Des/Assembly Top")
		(33 "B.Fab" user "Ref Des/Assembly Bottom")
	)
	(footprint ""
		(layer "F.Cu")
		(at 18.796 -210.439 180)
		(property "Reference" "R5317"
			(at 0 0 180)
			(layer "F.SilkS")
			(hide yes)
			(effects
				(font
					(size 1.27 1.27)
				)
			)
		)
		(property "Value" ""
			(at 0 0 180)
			(layer "F.Fab")
			(effects
				(font
					(size 1.27 1.27)
				)
			)
		)
		(duplicate_pad_numbers_are_jumpers no)
		(fp_line
			(start 1.2954 0.5842)
			(end -1.2954 0.5842)
			(stroke
				(width 0.1524)
				(type default)
			)
			(layer "F.SilkS")
		)
		(fp_line
			(start 1.2954 -0.5842)
			(end 1.2954 0.5842)
			(stroke
				(width 0.1524)
				(type default)
			)
			(layer "F.SilkS")
		)
		(fp_line
			(start -1.2954 0.5842)
			(end -1.2954 -0.5842)
			(stroke
				(width 0.1524)
				(type default)
			)
			(layer "F.SilkS")
		)
		(fp_line
			(start -1.2954 -0.5842)
			(end 1.2954 -0.5842)
			(stroke
				(width 0.1524)
				(type default)
			)
			(layer "F.SilkS")
		)
		(fp_line
			(start 1.1938 0.4064)
			(end 0.8636 0.4064)
			(stroke
				(width 0.1)
				(type default)
			)
			(layer "F.Fab")
		)
		(fp_line
			(start 1.1938 -0.406654)
			(end 1.1938 0.4064)
			(stroke
				(width 0.1)
				(type default)
			)
			(layer "F.Fab")
		)
		(fp_line
			(start 0.8636 0.4572)
			(end -0.8636 0.4572)
			(stroke
				(width 0.1)
				(type default)
			)
			(layer "F.Fab")
		)
		(fp_line
			(start 0.8636 0.4064)
			(end 0.8636 0.4572)
			(stroke
				(width 0.1)
				(type default)
			)
			(layer "F.Fab")
		)
		(fp_line
			(start 0.8636 -0.406654)
			(end 1.1938 -0.406654)
			(stroke
				(width 0.1)
				(type default)
			)
			(layer "F.Fab")
		)
		(fp_line
			(start 0.8636 -0.4572)
			(end 0.8636 -0.406654)
			(stroke
				(width 0.1)
				(type default)
			)
			(layer "F.Fab")
		)
		(fp_line
			(start -0.8636 0.4572)
			(end -0.8636 0.4318)
			(stroke
				(width 0.1)
				(type default)
			)
			(layer "F.Fab")
		)
		(fp_line
			(start -0.8636 0.4318)
			(end -0.8636 0.4064)
			(stroke
				(width 0.1)
				(type default)
			)
			(layer "F.Fab")
		)
		(fp_line
			(start -0.8636 0.4064)
			(end -1.1938 0.4064)
			(stroke
				(width 0.1)
				(type default)
			)
			(layer "F.Fab")
		)
		(fp_line
			(start -0.8636 -0.406654)
			(end -0.8636 -0.4572)
			(stroke
				(width 0.1)
				(type default)
			)
			(layer "F.Fab")
		)
		(fp_line
			(start -0.8636 -0.4572)
			(end 0.8636 -0.4572)
			(stroke
				(width 0.1)
				(type default)
			)
			(layer "F.Fab")
		)
		(fp_line
			(start -1.1938 0.4064)
			(end -1.1938 -0.406654)
			(stroke
				(width 0.1)
				(type default)
			)
			(layer "F.Fab")
		)
		(fp_line
			(start -1.1938 -0.406654)
			(end -0.8636 -0.406654)
			(stroke
				(width 0.1)
				(type default)
			)
			(layer "F.Fab")
		)
		(pad "1" smd rect
			(at -0.7366 0 90)
			(size 0.7112 0.8128)
			(layers "F.Cu" "F.Mask" "F.Paste")
			(net "P52V_FAN_6")
		)
		(pad "2" smd rect
			(at 0.7366 0 90)
			(size 0.7112 0.8128)
			(layers "F.Cu" "F.Mask" "F.Paste")
			(net "FAN_6_TACH_OL_R")
		)
	)
	(footprint ""
		(layer "F.Cu")
		(at 5.969 -31.496)
		(property "Reference" "R5704"
			(at 0 0 0)
			(layer "F.SilkS")
			(hide yes)
			(effects
				(font
					(size 1.27 1.27)
				)
			)
		)
		(property "Value" ""
			(at 0 0 0)
			(layer "F.Fab")
			(effects
				(font
					(size 1.27 1.27)
				)
			)
		)
		(duplicate_pad_numbers_are_jumpers no)
		(fp_line
			(start -0.7874 -0.4064)
			(end 0.7874 -0.4064)
			(stroke
				(width 0.1524)
				(type default)
			)
			(layer "F.SilkS")
		)
		(fp_line
			(start -0.7874 0.4064)
			(end -0.7874 -0.4064)
			(stroke
				(width 0.1524)
				(type default)
			)
			(layer "F.SilkS")
		)
		(fp_line
			(start 0.7874 -0.4064)
			(end 0.7874 0.4064)
			(stroke
				(width 0.1524)
				(type default)
			)
			(layer "F.SilkS")
		)
		(fp_line
			(start 0.7874 0.4064)
			(end -0.7874 0.4064)
			(stroke
				(width 0.1524)
				(type default)
			)
			(layer "F.SilkS")
		)
		(fp_line
			(start -0.67945 -0.305054)
			(end -0.12065 -0.305054)
			(stroke
				(width 0.1)
				(type default)
			)
			(layer "F.Fab")
		)
		(fp_line
			(start -0.67945 0.3048)
			(end -0.67945 -0.305054)
			(stroke
				(width 0.1)
				(type default)
			)
			(layer "F.Fab")
		)
		(fp_line
			(start -0.12065 -0.305054)
			(end -0.12065 -0.2794)
			(stroke
				(width 0.1)
				(type default)
			)
			(layer "F.Fab")
		)
		(fp_line
			(start -0.12065 -0.2794)
			(end 0.12065 -0.2794)
			(stroke
				(width 0.1)
				(type default)
			)
			(layer "F.Fab")
		)
		(fp_line
			(start -0.12065 0.2794)
			(end -0.12065 0.3048)
			(stroke
				(width 0.1)
				(type default)
			)
			(layer "F.Fab")
		)
		(fp_line
			(start -0.12065 0.3048)
			(end -0.67945 0.3048)
			(stroke
				(width 0.1)
				(type default)
			)
			(layer "F.Fab")
		)
		(fp_line
			(start 0.120396 0.2794)
			(end -0.12065 0.2794)
			(stroke
				(width 0.1)
				(type default)
			)
			(layer "F.Fab")
		)
		(fp_line
			(start 0.120396 0.3048)
			(end 0.120396 0.2794)
			(stroke
				(width 0.1)
				(type default)
			)
			(layer "F.Fab")
		)
		(fp_line
			(start 0.12065 -0.3048)
			(end 0.67945 -0.3048)
			(stroke
				(width 0.1)
				(type default)
			)
			(layer "F.Fab")
		)
		(fp_line
			(start 0.12065 -0.2794)
			(end 0.12065 -0.3048)
			(stroke
				(width 0.1)
				(type default)
			)
			(layer "F.Fab")
		)
		(fp_line
			(start 0.67945 -0.3048)
			(end 0.67945 0.3048)
			(stroke
				(width 0.1)
				(type default)
			)
			(layer "F.Fab")
		)
		(fp_line
			(start 0.67945 0.3048)
			(end 0.120396 0.3048)
			(stroke
				(width 0.1)
				(type default)
			)
			(layer "F.Fab")
		)
		(pad "1" smd rect
			(at -0.40005 0 180)
			(size 0.4572 0.508)
			(layers "F.Cu" "F.Mask" "F.Paste")
			(net "P12V_LED_R_FAN4")
		)
		(pad "2" smd rect
			(at 0.40005 0 180)
			(size 0.4572 0.508)
			(layers "F.Cu" "F.Mask" "F.Paste")
			(net "P12V_LED_R1_FAN4")
		)
	)
	(footprint ""
		(layer "F.Cu")
		(at 14.859 -123.317)
		(property "Reference" "R5610"
			(at 0 0 0)
			(layer "F.SilkS")
			(hide yes)
			(effects
				(font
					(size 1.27 1.27)
				)
			)
		)
		(property "Value" ""
			(at 0 0 0)
			(layer "F.Fab")
			(effects
				(font
					(size 1.27 1.27)
				)
			)
		)
		(duplicate_pad_numbers_are_jumpers no)
		(fp_line
			(start -0.7874 -0.4064)
			(end 0.7874 -0.4064)
			(stroke
				(width 0.1524)
				(type default)
			)
			(layer "F.SilkS")
		)
		(fp_line
			(start -0.7874 0.4064)
			(end -0.7874 -0.4064)
			(stroke
				(width 0.1524)
				(type default)
			)
			(layer "F.SilkS")
		)
		(fp_line
			(start 0.7874 -0.4064)
			(end 0.7874 0.4064)
			(stroke
				(width 0.1524)
				(type default)
			)
			(layer "F.SilkS")
		)
		(fp_line
			(start 0.7874 0.4064)
			(end -0.7874 0.4064)
			(stroke
				(width 0.1524)
				(type default)
			)
			(layer "F.SilkS")
		)
		(fp_line
			(start -0.67945 -0.305054)
			(end -0.12065 -0.305054)
			(stroke
				(width 0.1)
				(type default)
			)
			(layer "F.Fab")
		)
		(fp_line
			(start -0.67945 0.3048)
			(end -0.67945 -0.305054)
			(stroke
				(width 0.1)
				(type default)
			)
			(layer "F.Fab")
		)
		(fp_line
			(start -0.12065 -0.305054)
			(end -0.12065 -0.2794)
			(stroke
				(width 0.1)
				(type default)
			)
			(layer "F.Fab")
		)
		(fp_line
			(start -0.12065 -0.2794)
			(end 0.12065 -0.2794)
			(stroke
				(width 0.1)
				(type default)
			)
			(layer "F.Fab")
		)
		(fp_line
			(start -0.12065 0.2794)
			(end -0.12065 0.3048)
			(stroke
				(width 0.1)
				(type default)
			)
			(layer "F.Fab")
		)
		(fp_line
			(start -0.12065 0.3048)
			(end -0.67945 0.3048)
			(stroke
				(width 0.1)
				(type default)
			)
			(layer "F.Fab")
		)
		(fp_line
			(start 0.120396 0.2794)
			(end -0.12065 0.2794)
			(stroke
				(width 0.1)
				(type default)
			)
			(layer "F.Fab")
		)
		(fp_line
			(start 0.120396 0.3048)
			(end 0.120396 0.2794)
			(stroke
				(width 0.1)
				(type default)
			)
			(layer "F.Fab")
		)
		(fp_line
			(start 0.12065 -0.3048)
			(end 0.67945 -0.3048)
			(stroke
				(width 0.1)
				(type default)
			)
			(layer "F.Fab")
		)
		(fp_line
			(start 0.12065 -0.2794)
			(end 0.12065 -0.3048)
			(stroke
				(width 0.1)
				(type default)
			)
			(layer "F.Fab")
		)
		(fp_line
			(start 0.67945 -0.3048)
			(end 0.67945 0.3048)
			(stroke
				(width 0.1)
				(type default)
			)
			(layer "F.Fab")
		)
		(fp_line
			(start 0.67945 0.3048)
			(end 0.120396 0.3048)
			(stroke
				(width 0.1)
				(type default)
			)
			(layer "F.Fab")
		)
		(pad "1" smd rect
			(at -0.40005 0 180)
			(size 0.4572 0.508)
			(layers "F.Cu" "F.Mask" "F.Paste")
			(net "FAN_4_TACH_IL")
		)
		(pad "2" smd rect
			(at 0.40005 0 180)
			(size 0.4572 0.508)
			(layers "F.Cu" "F.Mask" "F.Paste")
			(net "FAN_4_TACH_IL_R1")
		)
	)
	(footprint ""
		(layer "F.Cu")
		(at 32.004 -110.49)
		(property "Reference" "R5399"
			(at 0 0 0)
			(layer "F.SilkS")
			(hide yes)
			(effects
				(font
					(size 1.27 1.27)
				)
			)
		)
		(property "Value" ""
			(at 0 0 0)
			(layer "F.Fab")
			(effects
				(font
					(size 1.27 1.27)
				)
			)
		)
		(duplicate_pad_numbers_are_jumpers no)
		(fp_line
			(start -0.7874 -0.4064)
			(end 0.7874 -0.4064)
			(stroke
				(width 0.1524)
				(type default)
			)
			(layer "F.SilkS")
		)
		(fp_line
			(start -0.7874 0.4064)
			(end -0.7874 -0.4064)
			(stroke
				(width 0.1524)
				(type default)
			)
			(layer "F.SilkS")
		)
		(fp_line
			(start 0.7874 -0.4064)
			(end 0.7874 0.4064)
			(stroke
				(width 0.1524)
				(type default)
			)
			(layer "F.SilkS")
		)
		(fp_line
			(start 0.7874 0.4064)
			(end -0.7874 0.4064)
			(stroke
				(width 0.1524)
				(type default)
			)
			(layer "F.SilkS")
		)
		(fp_line
			(start -0.67945 -0.305054)
			(end -0.12065 -0.305054)
			(stroke
				(width 0.1)
				(type default)
			)
			(layer "F.Fab")
		)
		(fp_line
			(start -0.67945 0.3048)
			(end -0.67945 -0.305054)
			(stroke
				(width 0.1)
				(type default)
			)
			(layer "F.Fab")
		)
		(fp_line
			(start -0.12065 -0.305054)
			(end -0.12065 -0.2794)
			(stroke
				(width 0.1)
				(type default)
			)
			(layer "F.Fab")
		)
		(fp_line
			(start -0.12065 -0.2794)
			(end 0.12065 -0.2794)
			(stroke
				(width 0.1)
				(type default)
			)
			(layer "F.Fab")
		)
		(fp_line
			(start -0.12065 0.2794)
			(end -0.12065 0.3048)
			(stroke
				(width 0.1)
				(type default)
			)
			(layer "F.Fab")
		)
		(fp_line
			(start -0.12065 0.3048)
			(end -0.67945 0.3048)
			(stroke
				(width 0.1)
				(type default)
			)
			(layer "F.Fab")
		)
		(fp_line
			(start 0.120396 0.2794)
			(end -0.12065 0.2794)
			(stroke
				(width 0.1)
				(type default)
			)
			(layer "F.Fab")
		)
		(fp_line
			(start 0.120396 0.3048)
			(end 0.120396 0.2794)
			(stroke
				(width 0.1)
				(type default)
			)
			(layer "F.Fab")
		)
		(fp_line
			(start 0.12065 -0.3048)
			(end 0.67945 -0.3048)
			(stroke
				(width 0.1)
				(type default)
			)
			(layer "F.Fab")
		)
		(fp_line
			(start 0.12065 -0.2794)
			(end 0.12065 -0.3048)
			(stroke
				(width 0.1)
				(type default)
			)
			(layer "F.Fab")
		)
		(fp_line
			(start 0.67945 -0.3048)
			(end 0.67945 0.3048)
			(stroke
				(width 0.1)
				(type default)
			)
			(layer "F.Fab")
		)
		(fp_line
			(start 0.67945 0.3048)
			(end 0.120396 0.3048)
			(stroke
				(width 0.1)
				(type default)
			)
			(layer "F.Fab")
		)
		(pad "1" smd circle
			(at -0.40005 0)
			(size 0 0)
			(layers "F.Cu" "F.Mask" "F.Paste")
			(net "P3V3_AUX")
		)
		(pad "2" smd circle
			(at 0.40005 0)
			(size 0 0)
			(layers "F.Cu" "F.Mask" "F.Paste")
			(net "FAN_2_FAIL_R_LED")
		)
	)
	(footprint ""
		(layer "F.Cu")
		(at 22.479 -298.45 90)
		(property "Reference" "R336"
			(at 0 0 90)
			(layer "F.SilkS")
			(hide yes)
			(effects
				(font
					(size 1.27 1.27)
				)
			)
		)
		(property "Value" ""
			(at 0 0 90)
			(layer "F.Fab")
			(effects
				(font
					(size 1.27 1.27)
				)
			)
		)
		(duplicate_pad_numbers_are_jumpers no)
		(fp_line
			(start 0.7874 -0.4064)
			(end 0.7874 0.4064)
			(stroke
				(width 0.1524)
				(type default)
			)
			(layer "F.SilkS")
		)
		(fp_line
			(start -0.7874 -0.4064)
			(end 0.7874 -0.4064)
			(stroke
				(width 0.1524)
				(type default)
			)
			(layer "F.SilkS")
		)
		(fp_line
			(start 0.7874 0.4064)
			(end -0.7874 0.4064)
			(stroke
				(width 0.1524)
				(type default)
			)
			(layer "F.SilkS")
		)
		(fp_line
			(start -0.7874 0.4064)
			(end -0.7874 -0.4064)
			(stroke
				(width 0.1524)
				(type default)
			)
			(layer "F.SilkS")
		)
		(fp_line
			(start -0.12065 -0.305054)
			(end -0.12065 -0.2794)
			(stroke
				(width 0.1)
				(type default)
			)
			(layer "F.Fab")
		)
		(fp_line
			(start -0.67945 -0.305054)
			(end -0.12065 -0.305054)
			(stroke
				(width 0.1)
				(type default)
			)
			(layer "F.Fab")
		)
		(fp_line
			(start 0.67945 -0.3048)
			(end 0.67945 0.3048)
			(stroke
				(width 0.1)
				(type default)
			)
			(layer "F.Fab")
		)
		(fp_line
			(start 0.12065 -0.3048)
			(end 0.67945 -0.3048)
			(stroke
				(width 0.1)
				(type default)
			)
			(layer "F.Fab")
		)
		(fp_line
			(start 0.12065 -0.2794)
			(end 0.12065 -0.3048)
			(stroke
				(width 0.1)
				(type default)
			)
			(layer "F.Fab")
		)
		(fp_line
			(start -0.12065 -0.2794)
			(end 0.12065 -0.2794)
			(stroke
				(width 0.1)
				(type default)
			)
			(layer "F.Fab")
		)
		(fp_line
			(start 0.120396 0.2794)
			(end -0.12065 0.2794)
			(stroke
				(width 0.1)
				(type default)
			)
			(layer "F.Fab")
		)
		(fp_line
			(start -0.12065 0.2794)
			(end -0.12065 0.3048)
			(stroke
				(width 0.1)
				(type default)
			)
			(layer "F.Fab")
		)
		(fp_line
			(start 0.67945 0.3048)
			(end 0.120396 0.3048)
			(stroke
				(width 0.1)
				(type default)
			)
			(layer "F.Fab")
		)
		(fp_line
			(start 0.120396 0.3048)
			(end 0.120396 0.2794)
			(stroke
				(width 0.1)
				(type default)
			)
			(layer "F.Fab")
		)
		(fp_line
			(start -0.12065 0.3048)
			(end -0.67945 0.3048)
			(stroke
				(width 0.1)
				(type default)
			)
			(layer "F.Fab")
		)
		(fp_line
			(start -0.67945 0.3048)
			(end -0.67945 -0.305054)
			(stroke
				(width 0.1)
				(type default)
			)
			(layer "F.Fab")
		)
		(pad "1" smd circle
			(at -0.40005 0 90)
			(size 0 0)
			(layers "F.Cu" "F.Mask" "F.Paste")
			(net "P3V3_AUX")
		)
		(pad "2" smd circle
			(at 0.40005 0 90)
			(size 0 0)
			(layers "F.Cu" "F.Mask" "F.Paste")
			(net "FAN_0_PWM")
		)
	)
	(footprint ""
		(layer "F.Cu")
		(at 14.351 -20.241768 180)
		(property "Reference" "R5131"
			(at 0 0 180)
			(layer "F.SilkS")
			(hide yes)
			(effects
				(font
					(size 1.27 1.27)
				)
			)
		)
		(property "Value" ""
			(at 0 0 180)
			(layer "F.Fab")
			(effects
				(font
					(size 1.27 1.27)
				)
			)
		)
		(duplicate_pad_numbers_are_jumpers no)
		(fp_line
			(start 0.7874 0.4064)
			(end -0.7874 0.4064)
			(stroke
				(width 0.1524)
				(type default)
			)
			(layer "F.SilkS")
		)
		(fp_line
			(start 0.7874 -0.4064)
			(end 0.7874 0.4064)
			(stroke
				(width 0.1524)
				(type default)
			)
			(layer "F.SilkS")
		)
		(fp_line
			(start -0.7874 0.4064)
			(end -0.7874 -0.4064)
			(stroke
				(width 0.1524)
				(type default)
			)
			(layer "F.SilkS")
		)
		(fp_line
			(start -0.7874 -0.4064)
			(end 0.7874 -0.4064)
			(stroke
				(width 0.1524)
				(type default)
			)
			(layer "F.SilkS")
		)
		(fp_line
			(start 0.67945 0.3048)
			(end 0.120396 0.3048)
			(stroke
				(width 0.1)
				(type default)
			)
			(layer "F.Fab")
		)
		(fp_line
			(start 0.67945 -0.3048)
			(end 0.67945 0.3048)
			(stroke
				(width 0.1)
				(type default)
			)
			(layer "F.Fab")
		)
		(fp_line
			(start 0.12065 -0.2794)
			(end 0.12065 -0.3048)
			(stroke
				(width 0.1)
				(type default)
			)
			(layer "F.Fab")
		)
		(fp_line
			(start 0.12065 -0.3048)
			(end 0.67945 -0.3048)
			(stroke
				(width 0.1)
				(type default)
			)
			(layer "F.Fab")
		)
		(fp_line
			(start 0.120396 0.3048)
			(end 0.120396 0.2794)
			(stroke
				(width 0.1)
				(type default)
			)
			(layer "F.Fab")
		)
		(fp_line
			(start 0.120396 0.2794)
			(end -0.12065 0.2794)
			(stroke
				(width 0.1)
				(type default)
			)
			(layer "F.Fab")
		)
		(fp_line
			(start -0.12065 0.3048)
			(end -0.67945 0.3048)
			(stroke
				(width 0.1)
				(type default)
			)
			(layer "F.Fab")
		)
		(fp_line
			(start -0.12065 0.2794)
			(end -0.12065 0.3048)
			(stroke
				(width 0.1)
				(type default)
			)
			(layer "F.Fab")
		)
		(fp_line
			(start -0.12065 -0.2794)
			(end 0.12065 -0.2794)
			(stroke
				(width 0.1)
				(type default)
			)
			(layer "F.Fab")
		)
		(fp_line
			(start -0.12065 -0.305054)
			(end -0.12065 -0.2794)
			(stroke
				(width 0.1)
				(type default)
			)
			(layer "F.Fab")
		)
		(fp_line
			(start -0.67945 0.3048)
			(end -0.67945 -0.305054)
			(stroke
				(width 0.1)
				(type default)
			)
			(layer "F.Fab")
		)
		(fp_line
			(start -0.67945 -0.305054)
			(end -0.12065 -0.305054)
			(stroke
				(width 0.1)
				(type default)
			)
			(layer "F.Fab")
		)
		(pad "1" smd circle
			(at -0.40005 0 180)
			(size 0 0)
			(layers "F.Cu" "F.Mask" "F.Paste")
			(net "SMB_FAN4_SCL")
		)
		(pad "2" smd circle
			(at 0.40005 0 180)
			(size 0 0)
			(layers "F.Cu" "F.Mask" "F.Paste")
			(net "SMB_FAN4_SCL_R")
		)
	)
)
